(kicad_pcb
	(version 20260206)
	(generator "pcbnew")
	(generator_version "10.0")
	(general
		(thickness 1.6)
		(legacy_teardrops no)
	)
	(paper "A4")
	(title_block
		(title "timecard-production-celestica-r4006 — R4006-B0001-02_R01.brd")
		(comment 1 "Time Appliance Project (Time Card) / footprints 86-90 of 1113")
	)
	(layers
		(0 "F.Cu" signal "TOP")
		(4 "In1.Cu" signal "L02_GND1")
		(6 "In2.Cu" signal "L03_SIG1")
		(8 "In3.Cu" signal "L04_GND2")
		(10 "In4.Cu" signal "L05_VCC1")
		(12 "In5.Cu" signal "L06_VCC2")
		(14 "In6.Cu" signal "L07_GND3")
		(16 "In7.Cu" signal "L08_SIG2")
		(18 "In8.Cu" signal "L09_GND4")
		(2 "B.Cu" signal "BOTTOM")
		(9 "F.Adhes" user "F.Adhesive")
		(11 "B.Adhes" user "B.Adhesive")
		(13 "F.Paste" user "Package Geometry/Pastemask Top")
		(15 "B.Paste" user "Package Geometry/Pastemask Bottom")
		(5 "F.SilkS" user "Ref Des/Silkscreen Top")
		(7 "B.SilkS" user "Ref Des/Silkscreen Bottom")
		(1 "F.Mask" user "Board Geometry/Soldermask Top")
		(3 "B.Mask" user "Board Geometry/Soldermask Bottom")
		(17 "Dwgs.User" user "User.Drawings")
		(19 "Cmts.User" user "User.Comments")
		(21 "Eco1.User" user "User.Eco1")
		(23 "Eco2.User" user "User.Eco2")
		(25 "Edge.Cuts" user "Board Geometry/Outline")
		(27 "Margin" user)
		(31 "F.CrtYd" user "Package Geometry/Place Bound Top")
		(29 "B.CrtYd" user "Package Geometry/Place Bound Bottom")
		(35 "F.Fab" user "Ref Des/Assembly Top")
		(33 "B.Fab" user "Ref Des/Assembly Bottom")
	)
	(footprint ""
		(layer "F.Cu")
		(at 16.383 -32.893)
		(property "Reference" "TP34"
			(at 1.69037 2.9972 90)
			(unlocked yes)
			(layer "F.SilkS")
			(effects
				(font
					(size 0.7874 0.5842)
					(thickness 0.1524)
				)
				(justify left)
			)
		)
		(property "Value" ""
			(at 0 0 0)
			(layer "F.Fab")
			(effects
				(font
					(size 1.27 1.27)
				)
			)
		)
		(property "Device Type" "TP_PIONT-TP010CT020B030_PTH-TPA"
			(at -1.341882 0.996696 0)
			(unlocked yes)
			(layer "F.Fab")
			(hide yes)
			(effects
				(font
					(size 0.7874 0.5842)
					(thickness 0.000001)
				)
				(justify left)
			)
		)
		(duplicate_pad_numbers_are_jumpers no)
		(fp_poly
			(pts
				(arc
					(start 0.889 0)
					(mid -0.889 0)
					(end 0.889 0)
				)
			)
			(stroke
				(width 0)
				(type default)
			)
			(fill no)
			(layer "B.CrtYd")
		)
		(fp_poly
			(pts
				(arc
					(start 0.889 0)
					(mid -0.889 0)
					(end 0.889 0)
				)
			)
			(stroke
				(width 0)
				(type default)
			)
			(fill no)
			(layer "F.CrtYd")
		)
		(pad "1" thru_hole circle
			(at 0 0)
			(size 0.508 0.508)
			(drill 0.254)
			(layers "*.Cu" "*.Mask")
			(remove_unused_layers no)
			(net "SMA3_SIG_OUT_BF_EN_N")
			(clearance 0.1016)
			(padstack
				(mode front_inner_back)
				(layer "Inner"
					(shape circle)
					(size 0.508 0.508)
					(clearance 0.1016)
				)
				(layer "B.Cu"
					(shape circle)
					(size 0.762 0.762)
					(clearance -0.0254)
				)
			)
		)
	)
	(footprint ""
		(layer "F.Cu")
		(at 10.922 -81.534 90)
		(property "Reference" "R398"
			(at -2.667 1.05537 90)
			(unlocked yes)
			(layer "F.SilkS")
			(effects
				(font
					(size 0.7874 0.5842)
					(thickness 0.1524)
				)
			)
		)
		(property "Value" "VAL*"
			(at 0.02032 2.13233 90)
			(unlocked yes)
			(layer "F.Fab")
			(hide yes)
			(effects
				(font
					(size 0.7874 0.5842)
					(thickness 0.1524)
				)
			)
		)
		(property "Tolerance" "TOL*"
			(at 0.044704 3.05435 90)
			(unlocked yes)
			(layer "Cmts.User")
			(hide yes)
			(effects
				(font
					(size 0.7874 0.5842)
					(thickness 0.1524)
				)
			)
		)
		(property "User Part Number" "PARTNUM*"
			(at 0.02032 4.024884 90)
			(unlocked yes)
			(layer "Cmts.User")
			(hide yes)
			(effects
				(font
					(size 0.7874 0.5842)
					(thickness 0.1524)
				)
			)
		)
		(property "Device Type" "RESISTOR-G155-133R0-01,33OHM,1%"
			(at 0.008382 1.210564 90)
			(unlocked yes)
			(layer "F.Fab")
			(hide yes)
			(effects
				(font
					(size 0.7874 0.5842)
					(thickness 0.1524)
				)
			)
		)
		(duplicate_pad_numbers_are_jumpers no)
		(fp_line
			(start 1.143 -0.5588)
			(end -1.143 -0.5588)
			(stroke
				(width 0.1)
				(type default)
			)
			(layer "F.SilkS")
		)
		(fp_line
			(start -1.143 -0.5588)
			(end -1.143 0.5588)
			(stroke
				(width 0.1)
				(type default)
			)
			(layer "F.SilkS")
		)
		(fp_line
			(start 1.143 0.5588)
			(end 1.143 -0.5588)
			(stroke
				(width 0.1)
				(type default)
			)
			(layer "F.SilkS")
		)
		(fp_line
			(start -1.143 0.5588)
			(end 1.143 0.5588)
			(stroke
				(width 0.1)
				(type default)
			)
			(layer "F.SilkS")
		)
		(fp_rect
			(start -1.143 -0.5588)
			(end 1.143 0.5588)
			(stroke
				(width 0)
				(type default)
			)
			(fill no)
			(layer "F.CrtYd")
		)
		(fp_line
			(start 0.508 -0.3048)
			(end -0.508 -0.3048)
			(stroke
				(width 0.1)
				(type default)
			)
			(layer "F.Fab")
		)
		(fp_line
			(start -0.508 -0.3048)
			(end -0.508 0.3048)
			(stroke
				(width 0.1)
				(type default)
			)
			(layer "F.Fab")
		)
		(fp_line
			(start 0.508 0.3048)
			(end 0.508 -0.3048)
			(stroke
				(width 0.1)
				(type default)
			)
			(layer "F.Fab")
		)
		(fp_line
			(start -0.508 0.3048)
			(end 0.508 0.3048)
			(stroke
				(width 0.1)
				(type default)
			)
			(layer "F.Fab")
		)
		(pad "1" smd rect
			(at -0.5334 0 90)
			(size 0.7112 0.6096)
			(layers "F.Cu" "F.Mask" "F.Paste")
			(net "GPS_SMA_LED_GREEN_N")
		)
		(pad "2" smd rect
			(at 0.5334 0 90)
			(size 0.7112 0.6096)
			(layers "F.Cu" "F.Mask" "F.Paste")
			(net "UNNAMED_14_LED4PV14_I269_4")
		)
		(zone
			(layer "F.Cu")
			(hatch none 0.5)
			(connect_pads
				(clearance 0)
			)
			(min_thickness 0.25)
			(keepout
				(tracks not_allowed)
				(vias allowed)
				(pads allowed)
				(copperpour not_allowed)
				(footprints allowed)
			)
			(placement
				(enabled no)
				(sheetname "")
			)
			(fill
				(thermal_gap 0.5)
				(thermal_bridge_width 0.5)
				(island_removal_mode 0)
			)
			(polygon
				(pts
					(xy 10.6172 -81.4578) (xy 11.2268 -81.4578) (xy 11.2268 -81.6102) (xy 10.6172 -81.6102)
				)
			)
		)
		(zone
			(layer "F.Cu")
			(hatch none 0.5)
			(connect_pads
				(clearance 0)
			)
			(min_thickness 0.25)
			(keepout
				(tracks allowed)
				(vias not_allowed)
				(pads allowed)
				(copperpour not_allowed)
				(footprints allowed)
			)
			(placement
				(enabled no)
				(sheetname "")
			)
			(fill
				(thermal_gap 0.5)
				(thermal_bridge_width 0.5)
				(island_removal_mode 0)
			)
			(polygon
				(pts
					(xy 10.6172 -81.4578) (xy 11.2268 -81.4578) (xy 11.2268 -81.6102) (xy 10.6172 -81.6102)
				)
			)
		)
	)
	(footprint ""
		(layer "F.Cu")
		(at 7.500112 -9.349994)
		(property "Reference" "ME10"
			(at -4.325112 2.531364 0)
			(unlocked yes)
			(layer "F.SilkS")
			(effects
				(font
					(size 0.7874 0.5842)
					(thickness 0.1524)
				)
			)
		)
		(property "Value" ""
			(at 0 0 0)
			(layer "F.Fab")
			(effects
				(font
					(size 1.27 1.27)
				)
			)
		)
		(property "Device Type" "MEC_MTH8-MTH125C236N_V8-MTH125A"
			(at 0 5.08127 0)
			(unlocked yes)
			(layer "F.Fab")
			(hide yes)
			(effects
				(font
					(size 0.7874 0.5842)
					(thickness 0.1524)
				)
			)
		)
		(duplicate_pad_numbers_are_jumpers no)
		(fp_poly
			(pts
				(arc
					(start 3.5052 0)
					(mid -3.5052 0)
					(end 3.5052 0)
				)
			)
			(stroke
				(width 0)
				(type default)
			)
			(fill no)
			(layer "B.CrtYd")
		)
		(fp_poly
			(pts
				(arc
					(start 3.5052 0)
					(mid -3.5052 0)
					(end 3.5052 0)
				)
			)
			(stroke
				(width 0)
				(type default)
			)
			(fill no)
			(layer "F.CrtYd")
		)
		(fp_circle
			(center 0 0)
			(end 2.9972 0)
			(stroke
				(width 0.1)
				(type default)
			)
			(fill no)
			(layer "B.Fab")
		)
		(fp_circle
			(center 0 0)
			(end 2.9972 0)
			(stroke
				(width 0.1)
				(type default)
			)
			(fill no)
			(layer "F.Fab")
		)
		(pad "" np_thru_hole circle
			(at 0 0)
			(size 2.921 2.921)
			(drill 3.175)
			(layers "*.Cu" "*.Mask")
			(padstack
				(mode front_inner_back)
				(layer "Inner"
					(shape circle)
					(size 2.921 2.921)
					(clearance 0.4445)
				)
				(layer "B.Cu"
					(shape circle)
					(size 2.921 2.921)
				)
			)
		)
		(pad "1" thru_hole circle
			(at 0 -2.4511)
			(size 0.6096 0.6096)
			(drill 0.3048)
			(layers "*.Cu" "*.Mask")
			(remove_unused_layers no)
			(net "SG")
			(padstack
				(mode front_inner_back)
				(layer "Inner"
					(shape circle)
					(size 0.6096 0.6096)
					(clearance 0.1143)
				)
				(layer "B.Cu"
					(shape circle)
					(size 0.6096 0.6096)
				)
			)
		)
		(pad "2" thru_hole circle
			(at 1.733296 -1.733296)
			(size 0.6096 0.6096)
			(drill 0.3048)
			(layers "*.Cu" "*.Mask")
			(remove_unused_layers no)
			(net "SG")
			(padstack
				(mode front_inner_back)
				(layer "Inner"
					(shape circle)
					(size 0.6096 0.6096)
					(clearance 0.1143)
				)
				(layer "B.Cu"
					(shape circle)
					(size 0.6096 0.6096)
				)
			)
		)
		(pad "3" thru_hole circle
			(at 2.4511 0)
			(size 0.6096 0.6096)
			(drill 0.3048)
			(layers "*.Cu" "*.Mask")
			(remove_unused_layers no)
			(net "SG")
			(padstack
				(mode front_inner_back)
				(layer "Inner"
					(shape circle)
					(size 0.6096 0.6096)
					(clearance 0.1143)
				)
				(layer "B.Cu"
					(shape circle)
					(size 0.6096 0.6096)
				)
			)
		)
		(pad "4" thru_hole circle
			(at 1.733296 1.733296)
			(size 0.6096 0.6096)
			(drill 0.3048)
			(layers "*.Cu" "*.Mask")
			(remove_unused_layers no)
			(net "SG")
			(padstack
				(mode front_inner_back)
				(layer "Inner"
					(shape circle)
					(size 0.6096 0.6096)
					(clearance 0.1143)
				)
				(layer "B.Cu"
					(shape circle)
					(size 0.6096 0.6096)
				)
			)
		)
		(pad "5" thru_hole circle
			(at 0 2.4511)
			(size 0.6096 0.6096)
			(drill 0.3048)
			(layers "*.Cu" "*.Mask")
			(remove_unused_layers no)
			(net "SG")
			(padstack
				(mode front_inner_back)
				(layer "Inner"
					(shape circle)
					(size 0.6096 0.6096)
					(clearance 0.1143)
				)
				(layer "B.Cu"
					(shape circle)
					(size 0.6096 0.6096)
				)
			)
		)
		(pad "6" thru_hole circle
			(at -1.733296 1.733296)
			(size 0.6096 0.6096)
			(drill 0.3048)
			(layers "*.Cu" "*.Mask")
			(remove_unused_layers no)
			(net "SG")
			(padstack
				(mode front_inner_back)
				(layer "Inner"
					(shape circle)
					(size 0.6096 0.6096)
					(clearance 0.1143)
				)
				(layer "B.Cu"
					(shape circle)
					(size 0.6096 0.6096)
				)
			)
		)
		(pad "7" thru_hole circle
			(at -2.4511 0)
			(size 0.6096 0.6096)
			(drill 0.3048)
			(layers "*.Cu" "*.Mask")
			(remove_unused_layers no)
			(net "SG")
			(padstack
				(mode front_inner_back)
				(layer "Inner"
					(shape circle)
					(size 0.6096 0.6096)
					(clearance 0.1143)
				)
				(layer "B.Cu"
					(shape circle)
					(size 0.6096 0.6096)
				)
			)
		)
		(pad "8" thru_hole circle
			(at -1.733296 -1.733296)
			(size 0.6096 0.6096)
			(drill 0.3048)
			(layers "*.Cu" "*.Mask")
			(remove_unused_layers no)
			(net "SG")
			(padstack
				(mode front_inner_back)
				(layer "Inner"
					(shape circle)
					(size 0.6096 0.6096)
					(clearance 0.1143)
				)
				(layer "B.Cu"
					(shape circle)
					(size 0.6096 0.6096)
				)
			)
		)
		(zone
			(layers "F.Cu" "B.Cu" "In1.Cu" "In2.Cu" "In3.Cu" "In4.Cu" "In5.Cu" "In6.Cu"
				"In7.Cu" "In8.Cu"
			)
			(hatch none 0.5)
			(connect_pads
				(clearance 0)
			)
			(min_thickness 0.25)
			(keepout
				(tracks not_allowed)
				(vias allowed)
				(pads allowed)
				(copperpour not_allowed)
				(footprints allowed)
			)
			(placement
				(enabled no)
				(sheetname "")
			)
			(fill
				(thermal_gap 0.5)
				(thermal_bridge_width 0.5)
				(island_removal_mode 0)
			)
			(polygon
				(pts
					(arc
						(start 9.392412 -9.349994)
						(mid 5.607812 -9.349994)
						(end 9.392412 -9.349994)
					)
				)
			)
		)
	)
	(footprint ""
		(layer "F.Cu")
		(at 150.381462 -56.8706)
		(property "Reference" "R296"
			(at -1.410462 -3.66903 0)
			(unlocked yes)
			(layer "F.SilkS")
			(effects
				(font
					(size 0.7874 0.5842)
					(thickness 0.1524)
				)
			)
		)
		(property "Value" "VAL*"
			(at 0.02032 2.13233 0)
			(unlocked yes)
			(layer "F.Fab")
			(hide yes)
			(effects
				(font
					(size 0.7874 0.5842)
					(thickness 0.1524)
				)
			)
		)
		(property "Tolerance" "TOL*"
			(at 0.044704 3.05435 0)
			(unlocked yes)
			(layer "Cmts.User")
			(hide yes)
			(effects
				(font
					(size 0.7874 0.5842)
					(thickness 0.1524)
				)
			)
		)
		(property "User Part Number" "PARTNUM*"
			(at 0.02032 4.024884 0)
			(unlocked yes)
			(layer "Cmts.User")
			(hide yes)
			(effects
				(font
					(size 0.7874 0.5842)
					(thickness 0.1524)
				)
			)
		)
		(property "Device Type" "RESISTOR-G155-14701-01,4.7KOHMA"
			(at 0.008382 1.210564 0)
			(unlocked yes)
			(layer "F.Fab")
			(hide yes)
			(effects
				(font
					(size 0.7874 0.5842)
					(thickness 0.1524)
				)
			)
		)
		(duplicate_pad_numbers_are_jumpers no)
		(fp_line
			(start -1.143 -0.5588)
			(end -1.143 0.5588)
			(stroke
				(width 0.1)
				(type default)
			)
			(layer "F.SilkS")
		)
		(fp_line
			(start -1.143 0.5588)
			(end 1.143 0.5588)
			(stroke
				(width 0.1)
				(type default)
			)
			(layer "F.SilkS")
		)
		(fp_line
			(start 1.143 -0.5588)
			(end -1.143 -0.5588)
			(stroke
				(width 0.1)
				(type default)
			)
			(layer "F.SilkS")
		)
		(fp_line
			(start 1.143 0.5588)
			(end 1.143 -0.5588)
			(stroke
				(width 0.1)
				(type default)
			)
			(layer "F.SilkS")
		)
		(fp_rect
			(start 1.143 -0.5588)
			(end -1.143 0.5588)
			(stroke
				(width 0)
				(type default)
			)
			(fill no)
			(layer "F.CrtYd")
		)
		(fp_line
			(start -0.508 -0.3048)
			(end -0.508 0.3048)
			(stroke
				(width 0.1)
				(type default)
			)
			(layer "F.Fab")
		)
		(fp_line
			(start -0.508 0.3048)
			(end 0.508 0.3048)
			(stroke
				(width 0.1)
				(type default)
			)
			(layer "F.Fab")
		)
		(fp_line
			(start 0.508 -0.3048)
			(end -0.508 -0.3048)
			(stroke
				(width 0.1)
				(type default)
			)
			(layer "F.Fab")
		)
		(fp_line
			(start 0.508 0.3048)
			(end 0.508 -0.3048)
			(stroke
				(width 0.1)
				(type default)
			)
			(layer "F.Fab")
		)
		(pad "1" smd rect
			(at -0.5334 0)
			(size 0.7112 0.6096)
			(layers "F.Cu" "F.Mask" "F.Paste")
			(net "XP3R3V_FPGA")
		)
		(pad "2" smd rect
			(at 0.5334 0)
			(size 0.7112 0.6096)
			(layers "F.Cu" "F.Mask" "F.Paste")
			(net "R_SHT3X_RST_N")
		)
		(zone
			(layer "F.Cu")
			(hatch none 0.5)
			(connect_pads
				(clearance 0)
			)
			(min_thickness 0.25)
			(keepout
				(tracks allowed)
				(vias not_allowed)
				(pads allowed)
				(copperpour not_allowed)
				(footprints allowed)
			)
			(placement
				(enabled no)
				(sheetname "")
			)
			(fill
				(thermal_gap 0.5)
				(thermal_bridge_width 0.5)
				(island_removal_mode 0)
			)
			(polygon
				(pts
					(xy 150.457662 -57.1754) (xy 150.305262 -57.1754) (xy 150.305262 -56.5658) (xy 150.457662 -56.5658)
				)
			)
		)
	)
	(footprint ""
		(layer "F.Cu")
		(at 110.9726 -26.7208 90)
		(property "Reference" "C252"
			(at -8.5598 -0.31623 90)
			(unlocked yes)
			(layer "F.SilkS")
			(effects
				(font
					(size 0.7874 0.5842)
					(thickness 0.1524)
				)
			)
		)
		(property "Value" "VAL*"
			(at 0.0762 2.067306 90)
			(unlocked yes)
			(layer "F.Fab")
			(hide yes)
			(effects
				(font
					(size 0.7874 0.5842)
					(thickness 0.1524)
				)
			)
		)
		(property "Device Type" "CAPACITOR-G105-0B104-CK,0.1UF,A"
			(at 0.0508 1.127506 90)
			(unlocked yes)
			(layer "F.Fab")
			(hide yes)
			(effects
				(font
					(size 0.7874 0.5842)
					(thickness 0.1524)
				)
			)
		)
		(property "User Part Number" "PARTNUM*"
			(at 0.1016 4.023106 90)
			(unlocked yes)
			(layer "Cmts.User")
			(hide yes)
			(effects
				(font
					(size 0.7874 0.5842)
					(thickness 0.1524)
				)
			)
		)
		(property "Tolerance" "TOL*"
			(at 0.0762 3.032506 90)
			(unlocked yes)
			(layer "Cmts.User")
			(hide yes)
			(effects
				(font
					(size 0.7874 0.5842)
					(thickness 0.1524)
				)
			)
		)
		(duplicate_pad_numbers_are_jumpers no)
		(fp_line
			(start 1.143 -0.5588)
			(end -1.143 -0.5588)
			(stroke
				(width 0.1)
				(type default)
			)
			(layer "F.SilkS")
		)
		(fp_line
			(start -1.143 -0.5588)
			(end -1.143 0.5588)
			(stroke
				(width 0.1)
				(type default)
			)
			(layer "F.SilkS")
		)
		(fp_line
			(start 1.143 0.5588)
			(end 1.143 -0.5588)
			(stroke
				(width 0.1)
				(type default)
			)
			(layer "F.SilkS")
		)
		(fp_line
			(start -1.143 0.5588)
			(end 1.143 0.5588)
			(stroke
				(width 0.1)
				(type default)
			)
			(layer "F.SilkS")
		)
		(fp_rect
			(start 1.143 -0.5588)
			(end -1.143 0.5588)
			(stroke
				(width 0)
				(type default)
			)
			(fill no)
			(layer "F.CrtYd")
		)
		(fp_line
			(start 0.508 -0.3048)
			(end -0.508 -0.3048)
			(stroke
				(width 0.1)
				(type default)
			)
			(layer "F.Fab")
		)
		(fp_line
			(start -0.508 -0.3048)
			(end -0.508 0.3048)
			(stroke
				(width 0.1)
				(type default)
			)
			(layer "F.Fab")
		)
		(fp_line
			(start 0.508 0.3048)
			(end 0.508 -0.3048)
			(stroke
				(width 0.1)
				(type default)
			)
			(layer "F.Fab")
		)
		(fp_line
			(start -0.508 0.3048)
			(end 0.508 0.3048)
			(stroke
				(width 0.1)
				(type default)
			)
			(layer "F.Fab")
		)
		(pad "1" smd rect
			(at -0.5334 0 90)
			(size 0.7112 0.6096)
			(layers "F.Cu" "F.Mask" "F.Paste")
			(net "OSC_200M_CLKN")
		)
		(pad "2" smd rect
			(at 0.5334 0 90)
			(size 0.7112 0.6096)
			(layers "F.Cu" "F.Mask" "F.Paste")
			(net "MHZ200CLKN_CLKIN")
		)
		(zone
			(layer "F.Cu")
			(hatch none 0.5)
			(connect_pads
				(clearance 0)
			)
			(min_thickness 0.25)
			(keepout
				(tracks allowed)
				(vias not_allowed)
				(pads allowed)
				(copperpour not_allowed)
				(footprints allowed)
			)
			(placement
				(enabled no)
				(sheetname "")
			)
			(fill
				(thermal_gap 0.5)
				(thermal_bridge_width 0.5)
				(island_removal_mode 0)
			)
			(polygon
				(pts
					(xy 110.6678 -26.797) (xy 110.6678 -26.6446) (xy 111.2774 -26.6446) (xy 111.2774 -26.797)
				)
			)
		)
	)
)
